# S9S_MB_2U (Grand Teton) — schematic netlist excerpt (pin names and nets, part order shuffled) for the footprints in the layout excerpt that follows; sources: Cadence DE-HDL packaged netlist, KiCad conversion of 03242023_DA0F0TMBIJ0_F0T_Motherboard_J_brd_V01_OCP.brd

U208  74LVC1G08W57  74LVC1G08W5-7 IC  pkg SOT25-5_0-95_3X1-6  page 158
  A  = HP_OCP_V3_1_EN
  B  = HP_LVC3_OCP_V3_1_PRSNT2
  GND  = GND
  Y  = HP_LVC3_OCP_V3_1_EN
  VCC  = P3V3_AUX

R4598  Q_RES  1K 1% CHIP  pkg 0402LF  page 195 : A = FM_BOARD_BMC_SKU_ID2 ; B = GND
C840  Q_CAP_DIFFBUS  DIFF BUS_0.22UF 6.3V 20% X6S  pkg C0201  page 174 : \1\ = P5E_CPU0_PE1_TX_C_DN<14> ; \2\ = P5E_CPU0_PE1_TX_DN<14>

(kicad_pcb
	(version 20260206)
	(generator "pcbnew")
	(generator_version "10.0")
	(general
		(thickness 1.6)
		(legacy_teardrops no)
	)
	(paper "A4")
	(title_block
		(title "03242023_DA0F0TMBIJ0_F0T_Motherboard_J_brd_V01_OCP.brd")
		(comment 1 "Grand Teton / footprints 1713-1715 of 6105")
	)
	(layers
		(0 "F.Cu" signal "TOP")
		(4 "In1.Cu" signal "GND")
		(6 "In2.Cu" signal "IN1")
		(8 "In3.Cu" signal "GND1")
		(10 "In4.Cu" signal "IN2")
		(12 "In5.Cu" signal "GND2")
		(14 "In6.Cu" signal "IN3")
		(16 "In7.Cu" signal "GND3")
		(18 "In8.Cu" signal "VCC")
		(20 "In9.Cu" signal "VCC1")
		(22 "In10.Cu" signal "GND4")
		(24 "In11.Cu" signal "IN4")
		(26 "In12.Cu" signal "GND5")
		(28 "In13.Cu" signal "IN5")
		(30 "In14.Cu" signal "GND6")
		(32 "In15.Cu" signal "IN6")
		(34 "In16.Cu" signal "GND7")
		(2 "B.Cu" signal "BOTTOM")
		(9 "F.Adhes" user "F.Adhesive")
		(11 "B.Adhes" user "B.Adhesive")
		(13 "F.Paste" user "Package Geometry/Pastemask Top")
		(15 "B.Paste" user "Package Geometry/Pastemask Bottom")
		(5 "F.SilkS" user "Ref Des/Silkscreen Top")
		(7 "B.SilkS" user "Ref Des/Silkscreen Bottom")
		(1 "F.Mask" user "Board Geometry/Soldermask Top")
		(3 "B.Mask" user "Board Geometry/Soldermask Bottom")
		(17 "Dwgs.User" user "User.Drawings")
		(19 "Cmts.User" user "User.Comments")
		(21 "Eco1.User" user "User.Eco1")
		(23 "Eco2.User" user "User.Eco2")
		(25 "Edge.Cuts" user "Board Geometry/Outline")
		(27 "Margin" user)
		(31 "F.CrtYd" user "Package Geometry/Place Bound Top")
		(29 "B.CrtYd" user "Package Geometry/Place Bound Bottom")
		(35 "F.Fab" user "Ref Des/Assembly Top")
		(33 "B.Fab" user "Ref Des/Assembly Bottom")
	)
	(footprint ""
		(layer "F.Cu")
		(at 174.1424 -94.338648 90)
		(property "Reference" "R4598"
			(at 0 0 90)
			(layer "F.SilkS")
			(hide yes)
			(effects
				(font
					(size 1.27 1.27)
				)
			)
		)
		(property "Value" ""
			(at 0 0 90)
			(layer "F.Fab")
			(effects
				(font
					(size 1.27 1.27)
				)
			)
		)
		(duplicate_pad_numbers_are_jumpers no)
		(fp_line
			(start 0.7874 -0.4064)
			(end 0.7874 0.4064)
			(stroke
				(width 0.1524)
				(type default)
			)
			(layer "F.SilkS")
		)
		(fp_line
			(start -0.7874 -0.4064)
			(end 0.7874 -0.4064)
			(stroke
				(width 0.1524)
				(type default)
			)
			(layer "F.SilkS")
		)
		(fp_line
			(start 0.7874 0.4064)
			(end -0.7874 0.4064)
			(stroke
				(width 0.1524)
				(type default)
			)
			(layer "F.SilkS")
		)
		(fp_line
			(start -0.7874 0.4064)
			(end -0.7874 -0.4064)
			(stroke
				(width 0.1524)
				(type default)
			)
			(layer "F.SilkS")
		)
		(fp_line
			(start -0.12065 -0.305054)
			(end -0.12065 -0.2794)
			(stroke
				(width 0.1)
				(type default)
			)
			(layer "F.Fab")
		)
		(fp_line
			(start -0.67945 -0.305054)
			(end -0.12065 -0.305054)
			(stroke
				(width 0.1)
				(type default)
			)
			(layer "F.Fab")
		)
		(fp_line
			(start 0.67945 -0.3048)
			(end 0.67945 0.3048)
			(stroke
				(width 0.1)
				(type default)
			)
			(layer "F.Fab")
		)
		(fp_line
			(start 0.12065 -0.3048)
			(end 0.67945 -0.3048)
			(stroke
				(width 0.1)
				(type default)
			)
			(layer "F.Fab")
		)
		(fp_line
			(start 0.12065 -0.2794)
			(end 0.12065 -0.3048)
			(stroke
				(width 0.1)
				(type default)
			)
			(layer "F.Fab")
		)
		(fp_line
			(start -0.12065 -0.2794)
			(end 0.12065 -0.2794)
			(stroke
				(width 0.1)
				(type default)
			)
			(layer "F.Fab")
		)
		(fp_line
			(start 0.120396 0.2794)
			(end -0.12065 0.2794)
			(stroke
				(width 0.1)
				(type default)
			)
			(layer "F.Fab")
		)
		(fp_line
			(start -0.12065 0.2794)
			(end -0.12065 0.3048)
			(stroke
				(width 0.1)
				(type default)
			)
			(layer "F.Fab")
		)
		(fp_line
			(start 0.67945 0.3048)
			(end 0.120396 0.3048)
			(stroke
				(width 0.1)
				(type default)
			)
			(layer "F.Fab")
		)
		(fp_line
			(start 0.120396 0.3048)
			(end 0.120396 0.2794)
			(stroke
				(width 0.1)
				(type default)
			)
			(layer "F.Fab")
		)
		(fp_line
			(start -0.12065 0.3048)
			(end -0.67945 0.3048)
			(stroke
				(width 0.1)
				(type default)
			)
			(layer "F.Fab")
		)
		(fp_line
			(start -0.67945 0.3048)
			(end -0.67945 -0.305054)
			(stroke
				(width 0.1)
				(type default)
			)
			(layer "F.Fab")
		)
		(pad "1" smd rect
			(at -0.40005 0 270)
			(size 0.4572 0.508)
			(layers "F.Cu" "F.Mask" "F.Paste")
			(net "FM_BOARD_BMC_SKU_ID2")
		)
		(pad "2" smd rect
			(at 0.40005 0 270)
			(size 0.4572 0.508)
			(layers "F.Cu" "F.Mask" "F.Paste")
			(net "GND")
		)
	)
	(footprint ""
		(layer "F.Cu")
		(at 392.809984 -17.612614 90)
		(property "Reference" "C840"
			(at 0 0 90)
			(layer "F.SilkS")
			(hide yes)
			(effects
				(font
					(size 1.27 1.27)
				)
			)
		)
		(property "Value" ""
			(at 0 0 90)
			(layer "F.Fab")
			(effects
				(font
					(size 1.27 1.27)
				)
			)
		)
		(duplicate_pad_numbers_are_jumpers no)
		(fp_line
			(start 0.299974 -0.150114)
			(end 0.299974 0.150114)
			(stroke
				(width 0.1)
				(type default)
			)
			(layer "F.Fab")
		)
		(fp_line
			(start -0.299974 -0.150114)
			(end 0.299974 -0.150114)
			(stroke
				(width 0.1)
				(type default)
			)
			(layer "F.Fab")
		)
		(fp_line
			(start 0.299974 0.150114)
			(end -0.299974 0.150114)
			(stroke
				(width 0.1)
				(type default)
			)
			(layer "F.Fab")
		)
		(fp_line
			(start -0.299974 0.150114)
			(end -0.299974 -0.150114)
			(stroke
				(width 0.1)
				(type default)
			)
			(layer "F.Fab")
		)
		(pad "1" smd rect
			(at -0.2667 0 90)
			(size 0.3048 0.381)
			(layers "F.Cu" "F.Mask" "F.Paste")
			(net "P5E_CPU0_PE1_TX_C_DN<14>")
		)
		(pad "2" smd rect
			(at 0.2667 0 90)
			(size 0.3048 0.381)
			(layers "F.Cu" "F.Mask" "F.Paste")
			(net "P5E_CPU0_PE1_TX_DN<14>")
		)
	)
	(footprint ""
		(layer "F.Cu")
		(at 449.43014 -114.112548 -90)
		(property "Reference" "U208"
			(at -0.582168 4.89458 0)
			(unlocked yes)
			(layer "F.SilkS")
			(effects
				(font
					(size 0.7874 0.5842)
					(thickness 0.1524)
				)
				(justify left)
			)
		)
		(property "Value" ""
			(at 0 0 270)
			(layer "F.Fab")
			(effects
				(font
					(size 1.27 1.27)
				)
			)
		)
		(duplicate_pad_numbers_are_jumpers no)
		(fp_line
			(start -1.733296 1.549908)
			(end 1.733296 1.549908)
			(stroke
				(width 0.1524)
				(type default)
			)
			(layer "F.SilkS")
		)
		(fp_line
			(start 1.733296 1.549908)
			(end 1.733296 -1.549908)
			(stroke
				(width 0.1524)
				(type default)
			)
			(layer "F.SilkS")
		)
		(fp_line
			(start 0 -0.889)
			(end -0.660908 -1.549908)
			(stroke
				(width 0.1524)
				(type default)
			)
			(layer "F.SilkS")
		)
		(fp_line
			(start -1.733296 -1.549908)
			(end -1.733296 1.549908)
			(stroke
				(width 0.1524)
				(type default)
			)
			(layer "F.SilkS")
		)
		(fp_line
			(start -0.660908 -1.549908)
			(end -1.733296 -1.549908)
			(stroke
				(width 0.1524)
				(type default)
			)
			(layer "F.SilkS")
		)
		(fp_line
			(start 0.660908 -1.549908)
			(end 0 -0.889)
			(stroke
				(width 0.1524)
				(type default)
			)
			(layer "F.SilkS")
		)
		(fp_line
			(start 1.733296 -1.549908)
			(end 0.660908 -1.549908)
			(stroke
				(width 0.1524)
				(type default)
			)
			(layer "F.SilkS")
		)
		(fp_poly
			(pts
				(xy -1.9304 -0.94996) (xy -2.4384 -0.69596) (xy -2.4384 -1.20396)
			)
			(stroke
				(width 0)
				(type default)
			)
			(fill yes)
			(layer "F.SilkS")
		)
		(fp_line
			(start -0.849884 1.549908)
			(end 0.849884 1.549908)
			(stroke
				(width 0.1)
				(type default)
			)
			(layer "F.Fab")
		)
		(fp_line
			(start 0.849884 1.549908)
			(end 0.849884 -1.549908)
			(stroke
				(width 0.1)
				(type default)
			)
			(layer "F.Fab")
		)
		(fp_line
			(start -0.849884 -1.549908)
			(end -0.849884 1.549908)
			(stroke
				(width 0.1)
				(type default)
			)
			(layer "F.Fab")
		)
		(fp_line
			(start 0.849884 -1.549908)
			(end -0.849884 -1.549908)
			(stroke
				(width 0.1)
				(type default)
			)
			(layer "F.Fab")
		)
		(fp_poly
			(pts
				(xy -2.4384 -1.20396) (xy -2.4384 -0.69596) (xy -1.9304 -0.94996)
			)
			(stroke
				(width 0)
				(type default)
			)
			(fill yes)
			(layer "F.Fab")
		)
		(pad "1" smd rect
			(at -1.199896 -0.94996 180)
			(size 0.5588 0.8128)
			(layers "F.Cu" "F.Mask" "F.Paste")
			(net "HP_OCP_V3_1_EN")
		)
		(pad "2" smd rect
			(at -1.199896 0 180)
			(size 0.5588 0.8128)
			(layers "F.Cu" "F.Mask" "F.Paste")
			(net "HP_LVC3_OCP_V3_1_PRSNT2")
		)
		(pad "3" smd rect
			(at -1.199896 0.94996 180)
			(size 0.5588 0.8128)
			(layers "F.Cu" "F.Mask" "F.Paste")
			(net "GND")
		)
		(pad "4" smd rect
			(at 1.199896 0.94996 180)
			(size 0.5588 0.8128)
			(layers "F.Cu" "F.Mask" "F.Paste")
			(net "HP_LVC3_OCP_V3_1_EN")
		)
		(pad "5" smd rect
			(at 1.199896 -0.94996 180)
			(size 0.5588 0.8128)
			(layers "F.Cu" "F.Mask" "F.Paste")
			(net "P3V3_AUX")
		)
	)
)
